(kicad_pcb
	(version 20241229)
	(generator "pcbnew")
	(generator_version "9.0")
	(general
		(thickness 1.711)
		(legacy_teardrops no)
	)
	(paper "A4")
	(title_block
		(title "Antmicro Baseboard for Jetson AGX Thor")
		(date "2026-02-18")
		(rev "1.1.0")
		(company "Antmicro Ltd")
		(comment 1 "www.antmicro.com")
		(comment 9 "footprints 73-76 of 1170")
	)
	(layers
		(0 "F.Cu" signal)
		(4 "In1.Cu" signal)
		(6 "In2.Cu" signal)
		(8 "In3.Cu" signal)
		(10 "In4.Cu" jumper)
		(12 "In5.Cu" signal)
		(14 "In6.Cu" signal)
		(16 "In7.Cu" signal)
		(18 "In8.Cu" signal)
		(2 "B.Cu" signal)
		(9 "F.Adhes" user "F.Adhesive")
		(11 "B.Adhes" user "B.Adhesive")
		(13 "F.Paste" user)
		(15 "B.Paste" user)
		(5 "F.SilkS" user "F.Silkscreen")
		(7 "B.SilkS" user "B.Silkscreen")
		(1 "F.Mask" user)
		(3 "B.Mask" user)
		(17 "Dwgs.User" user "User.Drawings")
		(19 "Cmts.User" user "User.Comments")
		(21 "Eco1.User" user "User.Eco1")
		(23 "Eco2.User" user "User.Eco2")
		(25 "Edge.Cuts" user)
		(27 "Margin" user)
		(31 "F.CrtYd" user "F.Courtyard")
		(29 "B.CrtYd" user "B.Courtyard")
		(35 "F.Fab" user)
		(33 "B.Fab" user)
	)
	(footprint "antmicro-footprints:C_0402_1005Metric"
		(layer "F.Cu")
		(at 203.25 57.25 90)
		(descr "Capacitor SMD 0402")
		(tags "capacitor SMD 0402")
		(property "Reference" "C239"
			(at -2 -0.5 90)
			(layer "F.SilkS")
			(effects
				(font
					(size 0.7 0.7)
					(thickness 0.15)
				)
				(justify left bottom)
			)
		)
		(property "Value" "C_100n_0402"
			(at -1.022927 2.155213 90)
			(layer "F.Fab")
			(effects
				(font
					(size 0.7 0.7)
					(thickness 0.15)
				)
				(justify left bottom)
			)
		)
		(property "Datasheet" "https://www.murata.com/products/productdetail?partno=GRM155R61H104KE14%23"
			(at 0 0 90)
			(layer "F.Fab")
			(hide yes)
			(effects
				(font
					(size 1.27 1.27)
					(thickness 0.15)
				)
			)
		)
		(property "Description" "SMD Multilayer Ceramic Capacitor, 0.1 µF, 50 V, 0402 [1005 Metric], ± 10%, X5R, GRM Series"
			(at 0 0 90)
			(layer "F.Fab")
			(hide yes)
			(effects
				(font
					(size 1.27 1.27)
					(thickness 0.15)
				)
			)
		)
		(property "MPN" "GRM155R61H104KE14D"
			(at 0 0 90)
			(unlocked yes)
			(layer "F.Fab")
			(hide yes)
			(effects
				(font
					(size 1 1)
					(thickness 0.15)
				)
			)
		)
		(property "Val" "100n"
			(at 0 0 90)
			(unlocked yes)
			(layer "F.Fab")
			(hide yes)
			(effects
				(font
					(size 1 1)
					(thickness 0.15)
				)
			)
		)
		(property "Voltage" "50V"
			(at 0 0 90)
			(unlocked yes)
			(layer "F.Fab")
			(hide yes)
			(effects
				(font
					(size 1 1)
					(thickness 0.15)
				)
			)
		)
		(property "Dielectric" "X5R"
			(at 0 0 90)
			(unlocked yes)
			(layer "F.Fab")
			(hide yes)
			(effects
				(font
					(size 1 1)
					(thickness 0.15)
				)
			)
		)
		(property "Manufacturer" "Murata"
			(at 0 0 90)
			(unlocked yes)
			(layer "F.Fab")
			(hide yes)
			(effects
				(font
					(size 1 1)
					(thickness 0.15)
				)
			)
		)
		(property "License" "Apache-2.0"
			(at 0 0 90)
			(unlocked yes)
			(layer "F.Fab")
			(hide yes)
			(effects
				(font
					(size 1 1)
					(thickness 0.15)
				)
			)
		)
		(property "Author" "Antmicro"
			(at 0 0 90)
			(unlocked yes)
			(layer "F.Fab")
			(hide yes)
			(effects
				(font
					(size 1 1)
					(thickness 0.15)
				)
			)
		)
		(sheetname "/SoM_Power/")
		(sheetfile "som_power.kicad_sch")
		(attr smd)
		(fp_poly
			(pts
				(xy -0.925 -0.47) (xy 0.925 -0.47) (xy 0.925 0.47) (xy -0.925 0.47)
			)
			(stroke
				(width 0.05)
				(type default)
			)
			(fill no)
			(layer "F.CrtYd")
		)
		(fp_line
			(start 0.504 -0.25)
			(end 0.504 0.248)
			(stroke
				(width 0.15)
				(type solid)
			)
			(layer "F.Fab")
		)
		(fp_line
			(start -0.494 -0.25)
			(end 0.504 -0.25)
			(stroke
				(width 0.15)
				(type solid)
			)
			(layer "F.Fab")
		)
		(fp_line
			(start 0.504 0.248)
			(end -0.494 0.248)
			(stroke
				(width 0.15)
				(type solid)
			)
			(layer "F.Fab")
		)
		(fp_line
			(start -0.494 0.248)
			(end -0.494 -0.25)
			(stroke
				(width 0.15)
				(type solid)
			)
			(layer "F.Fab")
		)
		(fp_text user "License: Apache-2.0"
			(at -0.939 5.799 90)
			(layer "F.Fab")
			(effects
				(font
					(size 0.7 0.7)
					(thickness 0.15)
				)
				(justify left bottom)
			)
		)
		(fp_text user "${REFERENCE}"
			(at -0.939 4.599 90)
			(layer "F.Fab")
			(effects
				(font
					(size 0.7 0.7)
					(thickness 0.15)
				)
				(justify left bottom)
			)
		)
		(fp_text user "Author: Antmicro"
			(at -0.939 3.399 90)
			(layer "F.Fab")
			(effects
				(font
					(size 0.7 0.7)
					(thickness 0.15)
				)
				(justify left bottom)
			)
		)
		(pad "1" smd roundrect
			(at -0.48 0 90)
			(size 0.59 0.64)
			(layers "F.Cu" "F.Mask" "F.Paste")
			(roundrect_rratio 0.25)
			(net 1 "GND")
			(pintype "passive")
		)
		(pad "2" smd roundrect
			(at 0.48 0 90)
			(size 0.59 0.64)
			(layers "F.Cu" "F.Mask" "F.Paste")
			(roundrect_rratio 0.25)
			(net 495 "/SoM_Power/~{FORCE_RECOVERY}")
			(pintype "passive")
		)
	)
	(footprint "antmicro-footprints:USON-10_2.5x1mm_P0.5mm"
		(layer "F.Cu")
		(at 221.369 99.26 180)
		(descr "USON-10 2.5x1mm_ Pitch 0.5mm")
		(tags "USON-10 2.5x1mm Pitch 0.5mm")
		(property "Reference" "U26"
			(at -0.961 0.64 90)
			(layer "F.SilkS")
			(effects
				(font
					(size 0.7 0.7)
					(thickness 0.15)
				)
				(justify right top)
			)
		)
		(property "Value" "TPD4E05U06QDQARQ1"
			(at 0.018 2.499 0)
			(layer "F.Fab")
			(effects
				(font
					(size 0.7 0.7)
					(thickness 0.15)
				)
				(justify right top)
			)
		)
		(property "Datasheet" "https://www.ti.com/lit/ds/symlink/tpd4e05u06-q1.pdf?HQS=dis-mous-null-mousermode-dsf-pf-null-wwe&ts=1663591265741&ref_url=https%253A%252F%252Fwww.mouser.com%252F"
			(at 0 0 0)
			(layer "F.Fab")
			(hide yes)
			(effects
				(font
					(size 1.27 1.27)
					(thickness 0.15)
				)
			)
		)
		(property "Description" "TVS diode array, 12 kV, USON-10, 5.5 V, 0.5 pF"
			(at 0 0 0)
			(layer "F.Fab")
			(hide yes)
			(effects
				(font
					(size 1.27 1.27)
					(thickness 0.15)
				)
			)
		)
		(property "Manufacturer" "Texas Instruments"
			(at 0 0 180)
			(unlocked yes)
			(layer "F.Fab")
			(hide yes)
			(effects
				(font
					(size 1 1)
					(thickness 0.15)
				)
			)
		)
		(property "MPN" "TPD4E05U06QDQARQ1"
			(at 0 0 180)
			(unlocked yes)
			(layer "F.Fab")
			(hide yes)
			(effects
				(font
					(size 1 1)
					(thickness 0.15)
				)
			)
		)
		(property "Author" "Antmicro"
			(at 0 0 180)
			(unlocked yes)
			(layer "F.Fab")
			(hide yes)
			(effects
				(font
					(size 1 1)
					(thickness 0.15)
				)
			)
		)
		(property "License" "Apache-2.0"
			(at 0 0 180)
			(unlocked yes)
			(layer "F.Fab")
			(hide yes)
			(effects
				(font
					(size 1 1)
					(thickness 0.15)
				)
			)
		)
		(sheetname "/Recovery USB/")
		(sheetfile "recovery_usb.kicad_sch")
		(attr smd)
		(fp_line
			(start 0.498 1.398)
			(end -0.5 1.398)
			(stroke
				(width 0.15)
				(type solid)
			)
			(layer "F.SilkS")
		)
		(fp_line
			(start 0.498 -1.401)
			(end -0.5 -1.401)
			(stroke
				(width 0.15)
				(type solid)
			)
			(layer "F.SilkS")
		)
		(fp_circle
			(center -0.68 -1.27)
			(end -0.63 -1.27)
			(stroke
				(width 0.15)
				(type solid)
			)
			(fill yes)
			(layer "F.SilkS")
		)
		(fp_rect
			(start -0.8 -1.5)
			(end 0.8 1.499)
			(stroke
				(width 0.05)
				(type solid)
			)
			(fill no)
			(layer "F.CrtYd")
		)
		(fp_line
			(start 0.498 -1.25)
			(end 0.498 1.249)
			(stroke
				(width 0.15)
				(type solid)
			)
			(layer "F.Fab")
		)
		(fp_line
			(start 0.498 -1.25)
			(end -0.25 -1.25)
			(stroke
				(width 0.15)
				(type solid)
			)
			(layer "F.Fab")
		)
		(fp_line
			(start -0.25 -1.25)
			(end -0.5 -1)
			(stroke
				(width 0.15)
				(type solid)
			)
			(layer "F.Fab")
		)
		(fp_line
			(start -0.5 1.249)
			(end 0.498 1.249)
			(stroke
				(width 0.15)
				(type solid)
			)
			(layer "F.Fab")
		)
		(fp_line
			(start -0.5 -1)
			(end -0.5 1.249)
			(stroke
				(width 0.15)
				(type solid)
			)
			(layer "F.Fab")
		)
		(fp_text user "License: Apache-2.0"
			(at -0.802 6.9 0)
			(layer "F.Fab")
			(effects
				(font
					(size 0.7 0.7)
					(thickness 0.15)
				)
				(justify right top)
			)
		)
		(fp_text user "Author: Antmicro"
			(at -0.802 5.7 0)
			(layer "F.Fab")
			(effects
				(font
					(size 0.7 0.7)
					(thickness 0.15)
				)
				(justify right top)
			)
		)
		(fp_text user "${REFERENCE}"
			(at -0.802 4.498 0)
			(layer "F.Fab")
			(effects
				(font
					(size 0.7 0.7)
					(thickness 0.15)
				)
				(justify right top)
			)
		)
		(pad "1" smd roundrect
			(at -0.387 -1 90)
			(size 0.25 0.55)
			(layers "F.Cu" "F.Mask" "F.Paste")
			(roundrect_rratio 0.25)
			(net 807 "/Recovery USB/USBC2_RX2_N")
			(pintype "passive")
		)
		(pad "2" smd roundrect
			(at -0.387 -0.5 90)
			(size 0.25 0.55)
			(layers "F.Cu" "F.Mask" "F.Paste")
			(roundrect_rratio 0.25)
			(net 804 "/Recovery USB/USBC2_RX2_P")
			(pintype "passive")
		)
		(pad "3" smd roundrect
			(at -0.387 0 90)
			(size 0.4 0.55)
			(layers "F.Cu" "F.Mask" "F.Paste")
			(roundrect_rratio 0.25)
			(net 1 "GND")
			(pintype "power_in")
		)
		(pad "4" smd roundrect
			(at -0.387 0.498 90)
			(size 0.25 0.55)
			(layers "F.Cu" "F.Mask" "F.Paste")
			(roundrect_rratio 0.25)
			(net 241 "/Recovery USB/USBC2_CONN_TX2_N")
			(pintype "passive")
		)
		(pad "5" smd roundrect
			(at -0.387 0.998 90)
			(size 0.25 0.55)
			(layers "F.Cu" "F.Mask" "F.Paste")
			(roundrect_rratio 0.25)
			(net 270 "/Recovery USB/USBC2_CONN_TX2_P")
			(pintype "passive")
		)
		(pad "6" smd roundrect
			(at 0.385 0.998 90)
			(size 0.25 0.55)
			(layers "F.Cu" "F.Mask" "F.Paste")
			(roundrect_rratio 0.25)
			(net 270 "/Recovery USB/USBC2_CONN_TX2_P")
			(pintype "passive")
		)
		(pad "7" smd roundrect
			(at 0.385 0.498 90)
			(size 0.25 0.55)
			(layers "F.Cu" "F.Mask" "F.Paste")
			(roundrect_rratio 0.25)
			(net 241 "/Recovery USB/USBC2_CONN_TX2_N")
			(pintype "passive")
		)
		(pad "8" smd roundrect
			(at 0.385 0 90)
			(size 0.4 0.55)
			(layers "F.Cu" "F.Mask" "F.Paste")
			(roundrect_rratio 0.25)
			(net 1 "GND")
			(pintype "passive")
		)
		(pad "9" smd roundrect
			(at 0.385 -0.5 90)
			(size 0.25 0.55)
			(layers "F.Cu" "F.Mask" "F.Paste")
			(roundrect_rratio 0.25)
			(net 804 "/Recovery USB/USBC2_RX2_P")
			(pintype "passive")
		)
		(pad "10" smd roundrect
			(at 0.385 -1 90)
			(size 0.25 0.55)
			(layers "F.Cu" "F.Mask" "F.Paste")
			(roundrect_rratio 0.25)
			(net 807 "/Recovery USB/USBC2_RX2_N")
			(pintype "passive")
		)
	)
	(footprint "antmicro-footprints:C_0402_1005Metric"
		(layer "F.Cu")
		(at 210.119132 92.592 180)
		(descr "Capacitor SMD 0402")
		(tags "capacitor SMD 0402")
		(property "Reference" "C132"
			(at 0.859132 -0.438 0)
			(layer "F.SilkS")
			(effects
				(font
					(size 0.7 0.7)
					(thickness 0.15)
				)
				(justify right top)
			)
		)
		(property "Value" "C_100n_0402"
			(at -1.022927 2.155213 0)
			(layer "F.Fab")
			(effects
				(font
					(size 0.7 0.7)
					(thickness 0.15)
				)
				(justify right top)
			)
		)
		(property "Datasheet" "https://www.murata.com/products/productdetail?partno=GRM155R61H104KE14%23"
			(at 0 0 0)
			(layer "F.Fab")
			(hide yes)
			(effects
				(font
					(size 1.27 1.27)
					(thickness 0.15)
				)
			)
		)
		(property "Description" "SMD Multilayer Ceramic Capacitor, 0.1 µF, 50 V, 0402 [1005 Metric], ± 10%, X5R, GRM Series"
			(at 0 0 0)
			(layer "F.Fab")
			(hide yes)
			(effects
				(font
					(size 1.27 1.27)
					(thickness 0.15)
				)
			)
		)
		(property "Manufacturer" "Murata"
			(at 0 0 180)
			(unlocked yes)
			(layer "F.Fab")
			(hide yes)
			(effects
				(font
					(size 1 1)
					(thickness 0.15)
				)
			)
		)
		(property "MPN" "GRM155R61H104KE14D"
			(at 0 0 180)
			(unlocked yes)
			(layer "F.Fab")
			(hide yes)
			(effects
				(font
					(size 1 1)
					(thickness 0.15)
				)
			)
		)
		(property "Val" "100n"
			(at 0 0 180)
			(unlocked yes)
			(layer "F.Fab")
			(hide yes)
			(effects
				(font
					(size 1 1)
					(thickness 0.15)
				)
			)
		)
		(property "License" "Apache-2.0"
			(at 0 0 180)
			(unlocked yes)
			(layer "F.Fab")
			(hide yes)
			(effects
				(font
					(size 1 1)
					(thickness 0.15)
				)
			)
		)
		(property "Author" "Antmicro"
			(at 0 0 180)
			(unlocked yes)
			(layer "F.Fab")
			(hide yes)
			(effects
				(font
					(size 1 1)
					(thickness 0.15)
				)
			)
		)
		(property "Voltage" "50V"
			(at 0 0 180)
			(unlocked yes)
			(layer "F.Fab")
			(hide yes)
			(effects
				(font
					(size 1 1)
					(thickness 0.15)
				)
			)
		)
		(property "Dielectric" "X5R"
			(at 0 0 180)
			(unlocked yes)
			(layer "F.Fab")
			(hide yes)
			(effects
				(font
					(size 1 1)
					(thickness 0.15)
				)
			)
		)
		(sheetname "/USB DP Alt mode/")
		(sheetfile "usb_dp.kicad_sch")
		(attr smd)
		(fp_rect
			(start -0.925 -0.47)
			(end 0.925 0.47)
			(stroke
				(width 0.05)
				(type default)
			)
			(fill no)
			(layer "F.CrtYd")
		)
		(fp_line
			(start 0.504 0.248)
			(end -0.494 0.248)
			(stroke
				(width 0.15)
				(type solid)
			)
			(layer "F.Fab")
		)
		(fp_line
			(start 0.504 -0.25)
			(end 0.504 0.248)
			(stroke
				(width 0.15)
				(type solid)
			)
			(layer "F.Fab")
		)
		(fp_line
			(start -0.494 0.248)
			(end -0.494 -0.25)
			(stroke
				(width 0.15)
				(type solid)
			)
			(layer "F.Fab")
		)
		(fp_line
			(start -0.494 -0.25)
			(end 0.504 -0.25)
			(stroke
				(width 0.15)
				(type solid)
			)
			(layer "F.Fab")
		)
		(fp_text user "Author: Antmicro"
			(at -0.939 3.399 0)
			(layer "F.Fab")
			(effects
				(font
					(size 0.7 0.7)
					(thickness 0.15)
				)
				(justify right top)
			)
		)
		(fp_text user "${REFERENCE}"
			(at -0.939 4.599 0)
			(layer "F.Fab")
			(effects
				(font
					(size 0.7 0.7)
					(thickness 0.15)
				)
				(justify right top)
			)
		)
		(fp_text user "License: Apache-2.0"
			(at -0.939 5.799 0)
			(layer "F.Fab")
			(effects
				(font
					(size 0.7 0.7)
					(thickness 0.15)
				)
				(justify right top)
			)
		)
		(pad "1" smd roundrect
			(at -0.48 0 180)
			(size 0.59 0.64)
			(layers "F.Cu" "F.Mask" "F.Paste")
			(roundrect_rratio 0.25)
			(net 2 "+3V3")
			(pintype "passive")
		)
		(pad "2" smd roundrect
			(at 0.48 0 180)
			(size 0.59 0.64)
			(layers "F.Cu" "F.Mask" "F.Paste")
			(roundrect_rratio 0.25)
			(net 1 "GND")
			(pintype "passive")
		)
	)
	(footprint "antmicro-footprints:R_0402_1005Metric"
		(layer "F.Cu")
		(at 232.540532 82.71 180)
		(descr "Resistor SMD 0402")
		(tags "resistor SMD 0402")
		(property "Reference" "R156"
			(at -1.122484 -0.772697 0)
			(layer "F.SilkS")
			(effects
				(font
					(size 0.7 0.7)
					(thickness 0.15)
				)
				(justify right top)
			)
		)
		(property "Value" "R_470R_0402"
			(at -1.011843 1.772046 0)
			(layer "F.Fab")
			(effects
				(font
					(size 0.7 0.7)
					(thickness 0.15)
				)
				(justify right top)
			)
		)
		(property "Datasheet" "https://www.bourns.com/docs/product-datasheets/cr.pdf"
			(at 0 0 0)
			(layer "F.Fab")
			(hide yes)
			(effects
				(font
					(size 1.27 1.27)
					(thickness 0.15)
				)
			)
		)
		(property "Description" "SMD Chip Resistor, 470 ohm, ± 1%, 62.5 mW, 0402 [1005 Metric], Thick Film, General Purpose"
			(at 0 0 0)
			(layer "F.Fab")
			(hide yes)
			(effects
				(font
					(size 1.27 1.27)
					(thickness 0.15)
				)
			)
		)
		(property "MPN" "CR0402-FX-4700GLF"
			(at 0 0 180)
			(unlocked yes)
			(layer "F.Fab")
			(hide yes)
			(effects
				(font
					(size 1 1)
					(thickness 0.15)
				)
			)
		)
		(property "Manufacturer" "Bourns"
			(at 0 0 180)
			(unlocked yes)
			(layer "F.Fab")
			(hide yes)
			(effects
				(font
					(size 1 1)
					(thickness 0.15)
				)
			)
		)
		(property "License" "Apache-2.0"
			(at 0 0 180)
			(unlocked yes)
			(layer "F.Fab")
			(hide yes)
			(effects
				(font
					(size 1 1)
					(thickness 0.15)
				)
			)
		)
		(property "Author" "Antmicro"
			(at 0 0 180)
			(unlocked yes)
			(layer "F.Fab")
			(hide yes)
			(effects
				(font
					(size 1 1)
					(thickness 0.15)
				)
			)
		)
		(property "Val" "470R"
			(at 0 0 180)
			(unlocked yes)
			(layer "F.Fab")
			(hide yes)
			(effects
				(font
					(size 1 1)
					(thickness 0.15)
				)
			)
		)
		(property "Tolerance" "1%"
			(at 0 0 180)
			(unlocked yes)
			(layer "F.Fab")
			(hide yes)
			(effects
				(font
					(size 1 1)
					(thickness 0.15)
				)
			)
		)
		(sheetname "/USB Debug, PD/")
		(sheetfile "usb_debug_pd.kicad_sch")
		(attr smd)
		(fp_poly
			(pts
				(xy -0.925 -0.47) (xy 0.925 -0.47) (xy 0.925 0.47) (xy -0.925 0.47)
			)
			(stroke
				(width 0.05)
				(type default)
			)
			(fill no)
			(layer "F.CrtYd")
		)
		(fp_poly
			(pts
				(xy -0.5 -0.25) (xy 0.5 -0.25) (xy 0.5 0.25) (xy -0.5 0.25)
			)
			(stroke
				(width 0.15)
				(type solid)
			)
			(fill no)
			(layer "F.Fab")
		)
		(fp_text user "Author: Antmicro"
			(at -0.95 4.169 0)
			(layer "F.Fab")
			(effects
				(font
					(size 0.7 0.7)
					(thickness 0.15)
				)
				(justify right top)
			)
		)
		(fp_text user "License: Apache-2.0"
			(at -0.949999 5.169 0)
			(layer "F.Fab")
			(effects
				(font
					(size 0.7 0.7)
					(thickness 0.15)
				)
				(justify right top)
			)
		)
		(fp_text user "${REFERENCE}"
			(at -0.95 3.168 0)
			(layer "F.Fab")
			(effects
				(font
					(size 0.7 0.7)
					(thickness 0.15)
				)
				(justify right top)
			)
		)
		(pad "1" smd roundrect
			(at -0.48 0 180)
			(size 0.59 0.64)
			(layers "F.Cu" "F.Mask" "F.Paste")
			(roundrect_rratio 0.25)
			(net 1387 "Net-(D24-A)")
			(pintype "passive")
		)
		(pad "2" smd roundrect
			(at 0.48 0 180)
			(size 0.59 0.64)
			(layers "F.Cu" "F.Mask" "F.Paste")
			(roundrect_rratio 0.25)
			(net 176 "/USB Debug, PD/USBC0_VBUS")
			(pintype "passive")
		)
	)
)
